FILE_TYPE = CONNECTIVITY;
{Allegro Design Entry HDL 17.2-2016 S081 (4005846) 1/11/2022}
"PAGE_NUMBER" = 88;
0"NC";
1"P3V3_AUX\g";
2"P12V_S3_AUX_CPU0_NVDIMM\g";
3"P3V3_AUX\g";
4"P12V_S3_AUX_CPU0_NVDIMM\g";
5"GND\g";
6"GND\g";
7"GND\g";
8"GND\g";
9"GND\g";
10"M_D_CPU0_SA_DQ<31:0>";
11"M_D_CPU0_SA_CB<7:0>";
12"M_D_CPU0_SB_CB<7:0>";
13"M_D_CPU0_SB_CA<6:0>";
14"M_D_CPU0_SA_CA<6:0>";
15"M_D_CPU0_SB_DQ<31:0>";
16"M_D_CPU0_SB_DQS_DP<9:0>";
17"M_D_CPU0_SA_DQS_DP<9:0>";
18"M_D_CPU0_SB_DQS_DN<9:0>";
19"M_D_CPU0_SA_DQS_DN<9:0>";
20"I3C_SPD_DDRABCD_CPU0_LVC1_SCL";
21"M_D_CPU0_ALERT_N";
22"I3C_SPD_DDRABCD_CPU0_LVC1_SDA";
23"PD_CHD_CPU0_DIMM1_SAA";
24"RST_M_CD_CPU0_FPGA_N";
25"M_D_CPU0_SB_CB<0>";
26"I3C_SPD_DDRABCD_CPU0_LVC1_SCL_R7";
27"PWRGD_CHD_CPU0_DIMM1";
28"M_D_CPU0_SA_DQS_DN<9>";
29"M_D_CPU0_SA_DQS_DN<8>";
30"M_D_CPU0_SA_DQS_DN<7>";
31"M_D_CPU0_SA_DQS_DN<6>";
32"M_D_CPU0_SA_DQS_DN<5>";
33"M_D_CPU0_SA_DQS_DN<4>";
34"M_D_CPU0_SA_DQS_DN<3>";
35"M_D_CPU0_SA_DQS_DN<2>";
36"M_D_CPU0_SA_DQS_DN<1>";
37"M_D_CPU0_SA_DQS_DN<0>";
38"M_D_CPU0_SB_DQS_DN<9>";
39"M_D_CPU0_SB_DQS_DN<8>";
40"M_D_CPU0_SB_DQS_DN<7>";
41"M_D_CPU0_SB_DQS_DN<6>";
42"M_D_CPU0_SB_DQS_DN<5>";
43"M_D_CPU0_SB_DQS_DN<4>";
44"M_D_CPU0_SB_DQS_DN<3>";
45"M_D_CPU0_SB_DQS_DN<2>";
46"M_D_CPU0_SB_DQS_DN<1>";
47"M_D_CPU0_SB_DQS_DN<0>";
48"M_D_CPU0_SA_DQS_DP<9>";
49"M_D_CPU0_SA_DQS_DP<8>";
50"M_D_CPU0_SA_DQS_DP<7>";
51"M_D_CPU0_SA_DQS_DP<6>";
52"M_D_CPU0_SA_DQS_DP<5>";
53"M_D_CPU0_SA_DQS_DP<4>";
54"M_D_CPU0_SA_DQS_DP<3>";
55"M_D_CPU0_SA_DQS_DP<2>";
56"M_D_CPU0_SA_DQS_DP<1>";
57"M_D_CPU0_SA_DQS_DP<0>";
58"M_D_CPU0_SB_DQS_DP<9>";
59"M_D_CPU0_SB_DQS_DP<8>";
60"M_D_CPU0_SB_DQS_DP<7>";
61"M_D_CPU0_SB_DQS_DP<6>";
62"M_D_CPU0_SB_DQS_DP<5>";
63"M_D_CPU0_SB_DQS_DP<4>";
64"M_D_CPU0_SB_DQS_DP<3>";
65"M_D_CPU0_SB_DQS_DP<2>";
66"M_D_CPU0_SB_DQS_DP<1>";
67"M_D_CPU0_SB_DQS_DP<0>";
68"M_D_CPU0_SA_DQ<29>";
69"M_D_CPU0_SA_DQ<30>";
70"M_D_CPU0_SA_DQ<28>";
71"M_D_CPU0_SA_DQ<26>";
72"M_D_CPU0_SA_CA<0>";
73"M_D_CPU0_SA_DQ<16>";
74"TP_CHD_CPU0_DIMM1_FRU_5";
75"TP_CHD_CPU0_DIMM1_FRU_6";
76"M_D_CPU0_SB_DQ<17>";
77"TP_CHD_CPU0_DIMM1_FRU_0";
78"TP_CHD_CPU0_DIMM1_FRU_1";
79"TP_CHD_CPU0_DIMM1_FRU_2";
80"TP_CHD_CPU0_DIMM1_FRU_3";
81"TP_CHD_CPU0_DIMM1_FRU_4";
82"M_D_CPU0_SB_PAR";
83"M_D_CPU0_SA_PAR";
84"M_D_CPU0_SB_RSP<0>";
85"M_D_CPU0_SA_RSP<0>";
86"M_D_CPU0_SB_DQ<0>";
87"M_D_CPU0_SB_DQ<1>";
88"M_D_CPU0_SB_DQ<2>";
89"M_D_CPU0_SB_DQ<3>";
90"M_D_CPU0_SB_DQ<4>";
91"M_D_CPU0_SB_DQ<5>";
92"M_D_CPU0_SB_DQ<6>";
93"M_D_CPU0_SB_DQ<7>";
94"M_D_CPU0_SB_DQ<8>";
95"M_D_CPU0_SB_DQ<9>";
96"M_D_CPU0_SB_DQ<10>";
97"M_D_CPU0_SB_DQ<11>";
98"M_D_CPU0_SB_DQ<12>";
99"M_D_CPU0_SB_DQ<13>";
100"M_D_CPU0_SB_DQ<14>";
101"M_D_CPU0_SB_DQ<15>";
102"M_D_CPU0_SB_DQ<16>";
103"M_D_CPU0_SB_DQ<18>";
104"M_D_CPU0_SB_DQ<19>";
105"M_D_CPU0_SB_DQ<20>";
106"M_D_CPU0_SB_DQ<21>";
107"M_D_CPU0_SB_DQ<22>";
108"M_D_CPU0_SB_DQ<23>";
109"M_D_CPU0_SB_DQ<24>";
110"M_D_CPU0_SB_DQ<25>";
111"M_D_CPU0_SB_DQ<26>";
112"M_D_CPU0_SB_DQ<27>";
113"M_D_CPU0_SB_DQ<28>";
114"M_D_CPU0_SB_DQ<29>";
115"M_D_CPU0_SB_DQ<30>";
116"M_D_CPU0_SB_DQ<31>";
117"M_D_CPU0_SA_DQ<0>";
118"M_D_CPU0_SA_DQ<1>";
119"M_D_CPU0_SA_DQ<2>";
120"M_D_CPU0_SA_DQ<3>";
121"M_D_CPU0_SA_DQ<4>";
122"M_D_CPU0_SA_DQ<5>";
123"M_D_CPU0_SA_DQ<6>";
124"M_D_CPU0_SA_DQ<7>";
125"M_D_CPU0_SA_DQ<8>";
126"M_D_CPU0_SA_DQ<9>";
127"M_D_CPU0_SA_DQ<10>";
128"M_D_CPU0_SA_DQ<11>";
129"M_D_CPU0_SA_DQ<12>";
130"M_D_CPU0_SA_DQ<13>";
131"M_D_CPU0_SA_DQ<14>";
132"M_D_CPU0_SA_DQ<15>";
133"M_D_CPU0_SA_DQ<17>";
134"M_D_CPU0_SA_DQ<18>";
135"M_D_CPU0_SA_DQ<19>";
136"M_D_CPU0_SA_DQ<20>";
137"M_D_CPU0_SA_DQ<21>";
138"M_D_CPU0_SA_DQ<22>";
139"M_D_CPU0_SA_DQ<23>";
140"M_D_CPU0_SA_DQ<24>";
141"M_D_CPU0_SA_DQ<25>";
142"M_D_CPU0_SA_DQ<27>";
143"M_D_CPU0_SB_CS_N<1>";
144"M_D_CPU0_SA_CS_N<1>";
145"M_D_CPU0_SB_CS_N<0>";
146"M_D_CPU0_SA_CS_N<0>";
147"M_D_CPU0_CLK_DP<0>";
148"M_D_CPU0_CLK_DN<0>";
149"M_D_CPU0_SB_CB<1>";
150"M_D_CPU0_SB_CB<2>";
151"M_D_CPU0_SB_CB<3>";
152"M_D_CPU0_SB_CB<4>";
153"M_D_CPU0_SB_CB<5>";
154"M_D_CPU0_SB_CB<6>";
155"M_D_CPU0_SA_CB<0>";
156"M_D_CPU0_SA_CB<2>";
157"M_D_CPU0_SA_CB<3>";
158"M_D_CPU0_SA_CB<5>";
159"M_D_CPU0_SA_CB<6>";
160"M_D_CPU0_SB_CA<6>";
161"M_D_CPU0_SA_CA<6>";
162"M_D_CPU0_SB_CA<5>";
163"M_D_CPU0_SA_CA<5>";
164"M_D_CPU0_SB_CA<4>";
165"M_D_CPU0_SA_CA<4>";
166"M_D_CPU0_SB_CA<3>";
167"M_D_CPU0_SA_CA<3>";
168"M_D_CPU0_SB_CA<2>";
169"M_D_CPU0_SA_CA<2>";
170"M_D_CPU0_SB_CA<1>";
171"M_D_CPU0_SA_CA<1>";
172"M_D_CPU0_SB_CA<0>";
173"M_D_CPU0_SB_CB<7>";
174"M_D_CPU0_SA_CB<1>";
175"M_D_CPU0_SA_CB<4>";
176"M_D_CPU0_SA_CB<7>";
177"M_D_CPU0_SA_DQ<31>";
178"PD_CHD_CPU0_DIMM1_SAA";
%"UNIVERSAL_GND"
"1","(-1675,-325)","0","logical_power","I1";
;
CDS_LIB"logical_power"
HDL_POWER"GND";
"A"5;
%"TAP"
"1","(-250,3350)","0","standard","I100";
;
CDS_LIB"standard"
BODY_TYPE"PLUMBING"
HDL_TAP"TRUE";
"B \NAC \NWC"10;
"S \NAC"
BN"17"133;
%"TAP"
"1","(-250,3300)","0","standard","I101";
;
CDS_LIB"standard"
BODY_TYPE"PLUMBING"
HDL_TAP"TRUE";
"B \NAC \NWC"10;
"S \NAC"
BN"16"73;
%"TAP"
"1","(-250,3450)","0","standard","I102";
;
CDS_LIB"standard"
BODY_TYPE"PLUMBING"
HDL_TAP"TRUE";
"B \NAC \NWC"10;
"S \NAC"
BN"19"135;
%"TAP"
"1","(-250,3400)","0","standard","I103";
;
CDS_LIB"standard"
BODY_TYPE"PLUMBING"
HDL_TAP"TRUE";
"B \NAC \NWC"10;
"S \NAC"
BN"18"134;
%"TAP"
"1","(-250,3500)","0","standard","I104";
;
CDS_LIB"standard"
BODY_TYPE"PLUMBING"
HDL_TAP"TRUE";
"B \NAC \NWC"10;
"S \NAC"
BN"20"136;
%"TAP"
"1","(-250,3600)","0","standard","I105";
;
CDS_LIB"standard"
BODY_TYPE"PLUMBING"
HDL_TAP"TRUE";
"B \NAC \NWC"10;
"S \NAC"
BN"22"138;
%"TAP"
"1","(-250,3550)","0","standard","I106";
;
CDS_LIB"standard"
BODY_TYPE"PLUMBING"
HDL_TAP"TRUE";
"B \NAC \NWC"10;
"S \NAC"
BN"21"137;
%"TAP"
"1","(-250,3650)","0","standard","I107";
;
CDS_LIB"standard"
BODY_TYPE"PLUMBING"
HDL_TAP"TRUE";
"B \NAC \NWC"10;
"S \NAC"
BN"23"139;
%"TAP"
"1","(-250,3700)","0","standard","I108";
;
CDS_LIB"standard"
BODY_TYPE"PLUMBING"
HDL_TAP"TRUE";
"B \NAC \NWC"10;
"S \NAC"
BN"24"140;
%"TAP"
"1","(-250,3800)","0","standard","I109";
;
CDS_LIB"standard"
BODY_TYPE"PLUMBING"
HDL_TAP"TRUE";
"B \NAC \NWC"10;
"S \NAC"
BN"26"71;
%"VCC_CORE"
"1","(-2725,1925)","0","logical_power","I11";
;
HDL_POWER"P3V3_AUX"
CDS_LIB"logical_power";
"A"1;
%"TAP"
"1","(-250,3750)","0","standard","I110";
;
CDS_LIB"standard"
BODY_TYPE"PLUMBING"
HDL_TAP"TRUE";
"B \NAC \NWC"10;
"S \NAC"
BN"25"141;
%"TAP"
"1","(-250,3850)","0","standard","I111";
;
CDS_LIB"standard"
BODY_TYPE"PLUMBING"
HDL_TAP"TRUE";
"B \NAC \NWC"10;
"S \NAC"
BN"27"142;
%"TAP"
"1","(-250,3950)","0","standard","I112";
;
CDS_LIB"standard"
BODY_TYPE"PLUMBING"
HDL_TAP"TRUE";
"B \NAC \NWC"10;
"S \NAC"
BN"29"68;
%"TAP"
"1","(-250,3900)","0","standard","I113";
;
CDS_LIB"standard"
BODY_TYPE"PLUMBING"
HDL_TAP"TRUE";
"B \NAC \NWC"10;
"S \NAC"
BN"28"70;
%"TAP"
"1","(-1900,4050)","2","standard","I116";
;
CDS_LIB"standard"
BODY_TYPE"PLUMBING"
HDL_TAP"TRUE";
"B \NAC \NWC"14;
"S \NAC"
BN"6"161;
%"TAP"
"1","(-1900,4000)","2","standard","I117";
;
CDS_LIB"standard"
BODY_TYPE"PLUMBING"
HDL_TAP"TRUE";
"B \NAC \NWC"14;
"S \NAC"
BN"5"163;
%"TAP"
"1","(-250,4050)","0","standard","I118";
;
CDS_LIB"standard"
BODY_TYPE"PLUMBING"
HDL_TAP"TRUE";
"B \NAC \NWC"10;
"S \NAC"
BN"31"177;
%"TAP"
"1","(-250,4000)","0","standard","I119";
;
CDS_LIB"standard"
BODY_TYPE"PLUMBING"
HDL_TAP"TRUE";
"B \NAC \NWC"10;
"S \NAC"
BN"30"69;
%"SCONN288_ADR50017P130CC"
"1","(-1075,2325)","0","pure_quanta","I12";
;
PART_NUMBER"DFHST8FS461"
MATERIAL"IO"
VALUE"SCONN288_ADR50017-P130CC"
PART_TYPE"SMLF"
$LOCATION"J7"
CDS_LIB"pure_quanta"
CDS_LMAN_SYM_OUTLINE"-450,1875,450,-1875"
NEEDS_NO_SIZE"TRUE"
CDS_LOCATION"J7"
$SEC"1"
CDS_SEC"1";
"DQ31_A"
$PN"194"177;
"CB7_A"
$PN"205"176;
"CB4_A"
$PN"58"175;
"CB1_A"
$PN"53"174;
"CB7_B"
$PN"236"173;
"ALERT_N \B"
$PN"62"21;
"CA0_A"
$PN"66"72;
"CA0_B"
$PN"76"172;
"CA1_A"
$PN"211"171;
"CA1_B"
$PN"221"170;
"CA2_A"
$PN"68"169;
"CA2_B"
$PN"78"168;
"CA3_A"
$PN"213"167;
"CA3_B"
$PN"223"166;
"CA4_A"
$PN"70"165;
"CA4_B"
$PN"80"164;
"CA5_A"
$PN"215"163;
"CA5_B"
$PN"225"162;
"CA6_A"
$PN"72"161;
"CA6_B"
$PN"82"160;
"CB6_A"
$PN"203"159;
"CB5_A"
$PN"60"158;
"CB3_A"
$PN"198"157;
"CB2_A"
$PN"196"156;
"CB0_A"
$PN"51"155;
"CB6_B"
$PN"234"154;
"CB5_B"
$PN"91"153;
"CB4_B"
$PN"89"152;
"CB3_B"
$PN"243"151;
"CB2_B"
$PN"241"150;
"CB1_B"
$PN"98"149;
"CB0_B"
$PN"96"25;
"CK_C \B"
$PN"218"148;
"CK_T"
$PN"217"147;
"CS0_A_N"
$PN"64"146;
"CS0_B_N"
$PN"84"145;
"CS1_A_N"
$PN"209"144;
"CS1_B_N"
$PN"229"143;
"DQ30_A"
$PN"192"69;
"DQ29_A"
$PN"49"68;
"DQ28_A"
$PN"47"70;
"DQ27_A"
$PN"187"142;
"DQ26_A"
$PN"185"71;
"DQ25_A"
$PN"42"141;
"DQ24_A"
$PN"40"140;
"DQ23_A"
$PN"183"139;
"DQ22_A"
$PN"181"138;
"DQ21_A"
$PN"38"137;
"DQ20_A"
$PN"36"136;
"DQ19_A"
$PN"176"135;
"DQ18_A"
$PN"174"134;
"DQ17_A"
$PN"31"133;
"DQ16_A"
$PN"29"73;
"DQ15_A"
$PN"172"132;
"DQ14_A"
$PN"170"131;
"DQ13_A"
$PN"27"130;
"DQ12_A"
$PN"25"129;
"DQ11_A"
$PN"165"128;
"DQ10_A"
$PN"163"127;
"DQ9_A"
$PN"20"126;
"DQ8_A"
$PN"18"125;
"DQ7_A"
$PN"161"124;
"DQ6_A"
$PN"159"123;
"DQ5_A"
$PN"16"122;
"DQ4_A"
$PN"14"121;
"DQ3_A"
$PN"154"120;
"DQ2_A"
$PN"152"119;
"DQ1_A"
$PN"9"118;
"DQ0_A"
$PN"7"117;
"DQ31_B"
$PN"287"116;
"DQ30_B"
$PN"285"115;
"DQ29_B"
$PN"142"114;
"DQ28_B"
$PN"140"113;
"DQ27_B"
$PN"280"112;
"DQ26_B"
$PN"278"111;
"DQ25_B"
$PN"135"110;
"DQ24_B"
$PN"133"109;
"DQ23_B"
$PN"276"108;
"DQ22_B"
$PN"274"107;
"DQ21_B"
$PN"131"106;
"DQ20_B"
$PN"129"105;
"DQ19_B"
$PN"269"104;
"DQ18_B"
$PN"267"103;
"DQ17_B"
$PN"124"76;
"DQ16_B"
$PN"122"102;
"DQ15_B"
$PN"265"101;
"DQ14_B"
$PN"263"100;
"DQ13_B"
$PN"120"99;
"DQ12_B"
$PN"118"98;
"DQ11_B"
$PN"258"97;
"DQ10_B"
$PN"256"96;
"DQ9_B"
$PN"113"95;
"DQ8_B"
$PN"111"94;
"DQ7_B"
$PN"254"93;
"DQ6_B"
$PN"252"92;
"DQ5_B"
$PN"109"91;
"DQ4_B"
$PN"107"90;
"DQ3_B"
$PN"247"89;
"DQ2_B"
$PN"245"88;
"DQ1_B"
$PN"102"87;
"DQ0_B"
$PN"100"86;
"HSA"
$PN"148"23;
"HSCL"
$PN"4"26;
"HSDA"
$PN"5"22;
"LBD||RSP_A_N"
$PN"86"85;
"LBS||RSP_B_N"
$PN"87"84;
"PAR_A"
$PN"74"83;
"PAR_B"
$PN"227"82;
"PWR_GOOD||FAIL_N"
$PN"147"27;
"RESET_N \B"
$PN"207"24;
"RFU6"
$PN"232"75;
"RFU5"
$PN"231"74;
"RFU4"
$PN"220"81;
"RFU3"
$PN"150"80;
"RFU2"
$PN"149"79;
"RFU1"
$PN"144"78;
"RFU0"
$PN"2"77;
"VIN_MGMT"
$PN"3"1;
%"UNIVERSAL_GND"
"1","(1475,-200)","0","logical_power","I121";
;
CDS_LIB"logical_power"
HDL_POWER"GND";
"A"6;
%"UNIVERSAL_GND"
"1","(3100,-200)","0","logical_power","I122";
;
CDS_LIB"logical_power"
HDL_POWER"GND";
"A"7;
%"Q_CAP"
"1","(1475,175)","0","pure_quanta","I123";
;
PART_NUMBER"CH5221MEB00"
VOLTAGE"6.3V"
MATERIAL"X6S"
VALUE"2.2UF"
TOLERANCE"20%"
PACK_TYPE"C0402"
$LOCATION"C20"
CDS_LIB"pure_quanta"
CDS_LOCATION"C20"
$SEC"1"
CDS_SEC"1";
"B"
$PN"2"6;
"A"
$PN"1"3;
%"VCC_CORE"
"1","(1475,500)","0","logical_power","I124";
;
HDL_POWER"P3V3_AUX"
CDS_LIB"logical_power";
"A"3;
%"Q_CAP"
"1","(2475,175)","0","pure_quanta","I126";
;
PART_NUMBER"CH6103KEA00"
MATERIAL"X6S"
PACK_TYPE"C0805"
TOLERANCE"10%"
VALUE"10UF"
VOLTAGE"16V"
$LOCATION"C21"
CDS_LIB"pure_quanta"
CDS_LOCATION"C21"
$SEC"1"
CDS_SEC"1";
"B"
$PN"2"7;
"A"
$PN"1"4;
%"VCC_CORE"
"1","(2475,500)","0","logical_power","I127";
;
HDL_POWER"P12V_S3_AUX_CPU0_NVDIMM"
CDS_LIB"logical_power";
"A"4;
%"TAP"
"1","(2500,2200)","0","standard","I128";
;
CDS_LIB"standard"
BODY_TYPE"PLUMBING"
HDL_TAP"TRUE";
"B \NAC \NWC"16;
"S \NAC"
BN"1"66;
%"TAP"
"1","(2500,2100)","0","standard","I129";
;
CDS_LIB"standard"
BODY_TYPE"PLUMBING"
HDL_TAP"TRUE";
"B \NAC \NWC"16;
"S \NAC"
BN"0"67;
%"TAP"
"1","(-1900,1850)","2","standard","I13";
;
CDS_LIB"standard"
BODY_TYPE"PLUMBING"
HDL_TAP"TRUE";
"B \NAC \NWC"12;
"S \NAC"
BN"0"25;
%"TAP"
"1","(2500,2300)","0","standard","I130";
;
CDS_LIB"standard"
BODY_TYPE"PLUMBING"
HDL_TAP"TRUE";
"B \NAC \NWC"16;
"S \NAC"
BN"2"65;
%"TAP"
"1","(2500,2400)","0","standard","I131";
;
CDS_LIB"standard"
BODY_TYPE"PLUMBING"
HDL_TAP"TRUE";
"B \NAC \NWC"16;
"S \NAC"
BN"3"64;
%"TAP"
"1","(2500,2500)","0","standard","I132";
;
CDS_LIB"standard"
BODY_TYPE"PLUMBING"
HDL_TAP"TRUE";
"B \NAC \NWC"16;
"S \NAC"
BN"4"63;
%"TAP"
"1","(2500,2700)","0","standard","I133";
;
CDS_LIB"standard"
BODY_TYPE"PLUMBING"
HDL_TAP"TRUE";
"B \NAC \NWC"16;
"S \NAC"
BN"6"61;
%"TAP"
"1","(2500,2600)","0","standard","I134";
;
CDS_LIB"standard"
BODY_TYPE"PLUMBING"
HDL_TAP"TRUE";
"B \NAC \NWC"16;
"S \NAC"
BN"5"62;
%"TAP"
"1","(2500,2800)","0","standard","I135";
;
CDS_LIB"standard"
BODY_TYPE"PLUMBING"
HDL_TAP"TRUE";
"B \NAC \NWC"16;
"S \NAC"
BN"7"60;
%"TAP"
"1","(2500,2900)","0","standard","I136";
;
CDS_LIB"standard"
BODY_TYPE"PLUMBING"
HDL_TAP"TRUE";
"B \NAC \NWC"16;
"S \NAC"
BN"8"59;
%"TAP"
"1","(2675,2050)","0","standard","I137";
;
CDS_LIB"standard"
BODY_TYPE"PLUMBING"
HDL_TAP"TRUE";
"B \NAC \NWC"18;
"S \NAC"
BN"0"47;
%"TAP"
"1","(2675,2150)","0","standard","I138";
;
CDS_LIB"standard"
BODY_TYPE"PLUMBING"
HDL_TAP"TRUE";
"B \NAC \NWC"18;
"S \NAC"
BN"1"46;
%"TAP"
"1","(2675,2250)","0","standard","I139";
;
CDS_LIB"standard"
BODY_TYPE"PLUMBING"
HDL_TAP"TRUE";
"B \NAC \NWC"18;
"S \NAC"
BN"2"45;
%"TAP"
"1","(-1900,1900)","2","standard","I14";
;
CDS_LIB"standard"
BODY_TYPE"PLUMBING"
HDL_TAP"TRUE";
"B \NAC \NWC"12;
"S \NAC"
BN"1"149;
%"TAP"
"1","(2675,2350)","0","standard","I140";
;
CDS_LIB"standard"
BODY_TYPE"PLUMBING"
HDL_TAP"TRUE";
"B \NAC \NWC"18;
"S \NAC"
BN"3"44;
%"TAP"
"1","(2675,2450)","0","standard","I141";
;
CDS_LIB"standard"
BODY_TYPE"PLUMBING"
HDL_TAP"TRUE";
"B \NAC \NWC"18;
"S \NAC"
BN"4"43;
%"TAP"
"1","(2675,2550)","0","standard","I142";
;
CDS_LIB"standard"
BODY_TYPE"PLUMBING"
HDL_TAP"TRUE";
"B \NAC \NWC"18;
"S \NAC"
BN"5"42;
%"TAP"
"1","(2675,2650)","0","standard","I143";
;
CDS_LIB"standard"
BODY_TYPE"PLUMBING"
HDL_TAP"TRUE";
"B \NAC \NWC"18;
"S \NAC"
BN"6"41;
%"TAP"
"1","(2675,2750)","0","standard","I144";
;
CDS_LIB"standard"
BODY_TYPE"PLUMBING"
HDL_TAP"TRUE";
"B \NAC \NWC"18;
"S \NAC"
BN"7"40;
%"TAP"
"1","(2675,2950)","0","standard","I145";
;
CDS_LIB"standard"
BODY_TYPE"PLUMBING"
HDL_TAP"TRUE";
"B \NAC \NWC"18;
"S \NAC"
BN"9"38;
%"TAP"
"1","(2675,2850)","0","standard","I146";
;
CDS_LIB"standard"
BODY_TYPE"PLUMBING"
HDL_TAP"TRUE";
"B \NAC \NWC"18;
"S \NAC"
BN"8"39;
%"TAP"
"1","(2500,3000)","0","standard","I147";
;
CDS_LIB"standard"
BODY_TYPE"PLUMBING"
HDL_TAP"TRUE";
"B \NAC \NWC"16;
"S \NAC"
BN"9"58;
%"TAP"
"1","(2500,3150)","0","standard","I148";
;
CDS_LIB"standard"
BODY_TYPE"PLUMBING"
HDL_TAP"TRUE";
"B \NAC \NWC"17;
"S \NAC"
BN"0"57;
%"TAP"
"1","(2500,3350)","0","standard","I149";
;
CDS_LIB"standard"
BODY_TYPE"PLUMBING"
HDL_TAP"TRUE";
"B \NAC \NWC"17;
"S \NAC"
BN"2"55;
%"TAP"
"1","(2500,3250)","0","standard","I150";
;
CDS_LIB"standard"
BODY_TYPE"PLUMBING"
HDL_TAP"TRUE";
"B \NAC \NWC"17;
"S \NAC"
BN"1"56;
%"TAP"
"1","(2500,3450)","0","standard","I151";
;
CDS_LIB"standard"
BODY_TYPE"PLUMBING"
HDL_TAP"TRUE";
"B \NAC \NWC"17;
"S \NAC"
BN"3"54;
%"TAP"
"1","(2500,3550)","0","standard","I152";
;
CDS_LIB"standard"
BODY_TYPE"PLUMBING"
HDL_TAP"TRUE";
"B \NAC \NWC"17;
"S \NAC"
BN"4"53;
%"TAP"
"1","(2500,3650)","0","standard","I153";
;
CDS_LIB"standard"
BODY_TYPE"PLUMBING"
HDL_TAP"TRUE";
"B \NAC \NWC"17;
"S \NAC"
BN"5"52;
%"TAP"
"1","(2500,3750)","0","standard","I154";
;
CDS_LIB"standard"
BODY_TYPE"PLUMBING"
HDL_TAP"TRUE";
"B \NAC \NWC"17;
"S \NAC"
BN"6"51;
%"TAP"
"1","(2500,3850)","0","standard","I155";
;
CDS_LIB"standard"
BODY_TYPE"PLUMBING"
HDL_TAP"TRUE";
"B \NAC \NWC"17;
"S \NAC"
BN"7"50;
%"TAP"
"1","(2500,3950)","0","standard","I156";
;
CDS_LIB"standard"
BODY_TYPE"PLUMBING"
HDL_TAP"TRUE";
"B \NAC \NWC"17;
"S \NAC"
BN"8"49;
%"TAP"
"1","(2675,3100)","0","standard","I157";
;
CDS_LIB"standard"
BODY_TYPE"PLUMBING"
HDL_TAP"TRUE";
"B \NAC \NWC"19;
"S \NAC"
BN"0"37;
%"TAP"
"1","(2675,3200)","0","standard","I158";
;
CDS_LIB"standard"
BODY_TYPE"PLUMBING"
HDL_TAP"TRUE";
"B \NAC \NWC"19;
"S \NAC"
BN"1"36;
%"TAP"
"1","(2675,3300)","0","standard","I159";
;
CDS_LIB"standard"
BODY_TYPE"PLUMBING"
HDL_TAP"TRUE";
"B \NAC \NWC"19;
"S \NAC"
BN"2"35;
%"TAP"
"1","(2675,3400)","0","standard","I160";
;
CDS_LIB"standard"
BODY_TYPE"PLUMBING"
HDL_TAP"TRUE";
"B \NAC \NWC"19;
"S \NAC"
BN"3"34;
%"TAP"
"1","(2675,3600)","0","standard","I161";
;
CDS_LIB"standard"
BODY_TYPE"PLUMBING"
HDL_TAP"TRUE";
"B \NAC \NWC"19;
"S \NAC"
BN"5"32;
%"TAP"
"1","(2675,3500)","0","standard","I162";
;
CDS_LIB"standard"
BODY_TYPE"PLUMBING"
HDL_TAP"TRUE";
"B \NAC \NWC"19;
"S \NAC"
BN"4"33;
%"TAP"
"1","(2675,3700)","0","standard","I163";
;
CDS_LIB"standard"
BODY_TYPE"PLUMBING"
HDL_TAP"TRUE";
"B \NAC \NWC"19;
"S \NAC"
BN"6"31;
%"TAP"
"1","(2675,3800)","0","standard","I164";
;
CDS_LIB"standard"
BODY_TYPE"PLUMBING"
HDL_TAP"TRUE";
"B \NAC \NWC"19;
"S \NAC"
BN"7"30;
%"TAP"
"1","(2675,3900)","0","standard","I165";
;
CDS_LIB"standard"
BODY_TYPE"PLUMBING"
HDL_TAP"TRUE";
"B \NAC \NWC"19;
"S \NAC"
BN"8"29;
%"Q_CAP"
"1","(3100,175)","0","pure_quanta","I166";
;
PART_NUMBER"CH6103KEA00"
MATERIAL"X6S"
PACK_TYPE"C0805"
VALUE"10UF"
TOLERANCE"10%"
VOLTAGE"16V"
$LOCATION"C22"
CDS_LIB"pure_quanta"
CDS_LOCATION"C22"
$SEC"1"
CDS_SEC"1";
"B"
$PN"2"7;
"A"
$PN"1"4;
%"UNIVERSAL_GND"
"1","(4175,350)","0","logical_power","I167";
;
CDS_LIB"logical_power"
HDL_POWER"GND";
"A"8;
%"SCONN288_ADR50017P130CC"
"3","(5025,2425)","0","pure_quanta","I168";
;
PART_NUMBER"DFHST8FS461"
VALUE"SCONN288_ADR50017-P130CC"
PART_TYPE"SMLF"
MATERIAL"IO"
$LOCATION"J7"
CDS_LIB"pure_quanta"
CDS_LMAN_SYM_OUTLINE"-450,1775,450,-1775"
NEEDS_NO_SIZE"TRUE"
CDS_LOCATION"J7"
$SEC"3"
CDS_SEC"3";
"G3"
$PN"G3"9;
"G2"
$PN"G2"9;
"G1"
$PN"G1"9;
"VSS62"
$PN"141"9;
"VSS61"
$PN"139"9;
"VSS60"
$PN"136"9;
"VSS58"
$PN"132"9;
"VSS104"
$PN"240"8;
"VSS102"
$PN"235"8;
"VSS100"
$PN"230"8;
"VIN_BULK2"
$PN"146"2;
"VIN_BULK1"
$PN"145"2;
"VIN_BULK0"
$PN"1"2;
"VSS126"
$PN"288"8;
"VSS125"
$PN"286"8;
"VSS124"
$PN"284"8;
"VSS123"
$PN"281"8;
"VSS122"
$PN"279"8;
"VSS121"
$PN"277"8;
"VSS120"
$PN"275"8;
"VSS119"
$PN"273"8;
"VSS118"
$PN"270"8;
"VSS117"
$PN"268"8;
"VSS116"
$PN"266"8;
"VSS115"
$PN"264"8;
"VSS114"
$PN"262"8;
"VSS113"
$PN"259"8;
"VSS112"
$PN"257"8;
"VSS111"
$PN"255"8;
"VSS110"
$PN"253"8;
"VSS109"
$PN"251"8;
"VSS108"
$PN"248"8;
"VSS107"
$PN"246"8;
"VSS106"
$PN"244"8;
"VSS105"
$PN"242"8;
"VSS103"
$PN"237"8;
"VSS101"
$PN"233"8;
"VSS99"
$PN"228"8;
"VSS98"
$PN"226"8;
"VSS97"
$PN"224"8;
"VSS96"
$PN"222"8;
"VSS95"
$PN"219"8;
"VSS94"
$PN"216"8;
"VSS93"
$PN"214"8;
"VSS92"
$PN"212"8;
"VSS91"
$PN"210"8;
"VSS90"
$PN"208"8;
"VSS89"
$PN"206"8;
"VSS88"
$PN"204"8;
"VSS87"
$PN"202"8;
"VSS86"
$PN"199"8;
"VSS85"
$PN"197"8;
"VSS84"
$PN"195"8;
"VSS83"
$PN"193"8;
"VSS82"
$PN"191"8;
"VSS81"
$PN"188"8;
"VSS80"
$PN"186"8;
"VSS79"
$PN"184"8;
"VSS78"
$PN"182"8;
"VSS77"
$PN"180"8;
"VSS76"
$PN"177"8;
"VSS75"
$PN"175"8;
"VSS74"
$PN"173"8;
"VSS73"
$PN"171"8;
"VSS72"
$PN"169"8;
"VSS71"
$PN"166"8;
"VSS70"
$PN"164"8;
"VSS69"
$PN"162"8;
"VSS68"
$PN"160"8;
"VSS67"
$PN"158"8;
"VSS66"
$PN"155"8;
"VSS65"
$PN"153"8;
"VSS64"
$PN"151"8;
"VSS63"
$PN"143"9;
"VSS59"
$PN"134"9;
"VSS57"
$PN"130"9;
"VSS56"
$PN"128"9;
"VSS55"
$PN"125"9;
"VSS54"
$PN"123"9;
"VSS53"
$PN"121"9;
"VSS52"
$PN"119"9;
"VSS51"
$PN"117"9;
"VSS50"
$PN"114"9;
"VSS49"
$PN"112"9;
"VSS48"
$PN"110"9;
"VSS47"
$PN"108"9;
"VSS46"
$PN"106"9;
"VSS45"
$PN"103"9;
"VSS44"
$PN"101"9;
"VSS43"
$PN"99"9;
"VSS42"
$PN"97"9;
"VSS41"
$PN"95"9;
"VSS40"
$PN"92"9;
"VSS39"
$PN"90"9;
"VSS38"
$PN"88"9;
"VSS37"
$PN"85"9;
"VSS36"
$PN"83"9;
"VSS35"
$PN"81"9;
"VSS34"
$PN"79"9;
"VSS33"
$PN"77"9;
"VSS32"
$PN"75"9;
"VSS31"
$PN"73"9;
"VSS30"
$PN"71"9;
"VSS29"
$PN"69"9;
"VSS28"
$PN"67"9;
"VSS27"
$PN"65"9;
"VSS26"
$PN"63"9;
"VSS25"
$PN"61"9;
"VSS24"
$PN"59"9;
"VSS23"
$PN"57"9;
"VSS22"
$PN"54"9;
"VSS21"
$PN"52"9;
"VSS20"
$PN"50"9;
"VSS19"
$PN"48"9;
"VSS18"
$PN"46"9;
"VSS17"
$PN"43"9;
"VSS16"
$PN"41"9;
"VSS15"
$PN"39"9;
"VSS14"
$PN"37"9;
"VSS13"
$PN"35"9;
"VSS12"
$PN"32"9;
"VSS11"
$PN"30"9;
"VSS10"
$PN"28"9;
"VSS9"
$PN"26"9;
"VSS8"
$PN"24"9;
"VSS7"
$PN"21"9;
"VSS6"
$PN"19"9;
"VSS5"
$PN"17"9;
"VSS4"
$PN"15"9;
"VSS3"
$PN"13"9;
"VSS2"
$PN"10"9;
"VSS1"
$PN"8"9;
"VSS0"
$PN"6"9;
%"TAP"
"1","(2500,4050)","0","standard","I172";
;
CDS_LIB"standard"
BODY_TYPE"PLUMBING"
HDL_TAP"TRUE";
"B \NAC \NWC"17;
"S \NAC"
BN"9"48;
%"TAP"
"1","(2675,4000)","0","standard","I173";
;
CDS_LIB"standard"
BODY_TYPE"PLUMBING"
HDL_TAP"TRUE";
"B \NAC \NWC"19;
"S \NAC"
BN"9"28;
%"VCC_CORE"
"1","(4175,4600)","0","logical_power","I175";
;
HDL_POWER"P12V_S3_AUX_CPU0_NVDIMM"
CDS_LIB"logical_power";
"A"2;
%"UNIVERSAL_GND"
"1","(5875,350)","0","logical_power","I176";
;
CDS_LIB"logical_power"
HDL_POWER"GND";
"A"9;
%"SCONN288_ADR50017P130CC"
"2","(1600,3050)","0","pure_quanta","I178";
;
PART_NUMBER"DFHST8FS461"
MATERIAL"IO"
VALUE"SCONN288_ADR50017-P130CC"
PART_TYPE"SMLF"
LOCATION"J7"
CDS_LMAN_SYM_OUTLINE"-600,1150,600,-1150"
CDS_LIB"pure_quanta"
NEEDS_NO_SIZE"TRUE"
$SEC"2"
CDS_SEC"2";
"DQS7_A_C||TDQS7_A_C \B"
$PN"178"30;
"DQS6_A_T||TDQS6_A_T"
$PN"168"51;
"DQS8_B_T||TDQS8_B_T"
$PN"283"59;
"DQS8_B_C||TDQS8_B_C \B"
$PN"282"39;
"DQS7_B_T||TDQS7_B_T"
$PN"272"60;
"DQS0_A_C \B"
$PN"12"37;
"DQS0_A_T"
$PN"11"57;
"DQS0_B_C \B"
$PN"105"47;
"DQS0_B_T"
$PN"104"67;
"DQS1_A_C \B"
$PN"23"36;
"DQS1_A_T"
$PN"22"56;
"DQS1_B_C \B"
$PN"116"46;
"DQS1_B_T"
$PN"115"66;
"DQS2_A_C \B"
$PN"34"35;
"DQS2_A_T"
$PN"33"55;
"DQS2_B_C \B"
$PN"127"45;
"DQS2_B_T"
$PN"126"65;
"DQS3_A_C \B"
$PN"45"34;
"DQS3_A_T"
$PN"44"54;
"DQS3_B_C \B"
$PN"138"44;
"DQS3_B_T"
$PN"137"64;
"DQS4_A_C \B"
$PN"56"33;
"DQS4_A_T"
$PN"55"53;
"DQS4_B_C \B"
$PN"238"43;
"DQS4_B_T"
$PN"239"63;
"DQS5_A_C||TDQS5_A_C||DQS5_A_T||TDQS5_A_T \B"
$PN"156"32;
"DQS5_A_T||TDQS5_A_T"
$PN"157"52;
"DQS5_B_C||TDQS5_B_C \B"
$PN"249"42;
"DQS5_B_T||TDQS5_B_T"
$PN"250"62;
"DQS6_A_C||TDQS6_A_C||DQS6_A_T||TDQS6_A_T \B"
$PN"167"31;
"DQS6_B_C||TDQS6_B_C \B"
$PN"260"41;
"DQS6_B_T||TDQS6_B_T"
$PN"261"61;
"DQS7_A_T||TDQS7_A_T"
$PN"179"50;
"DQS7_B_C||TDQS7_B_C \B"
$PN"271"40;
"DQS8_A_C||TDQS8_A_C \B"
$PN"189"29;
"DQS8_A_T||TDQS8_A_T"
$PN"190"49;
"DQS9_A_C||TDQS9_A_C \B"
$PN"200"28;
"DQS9_A_T||TDQS9_A_T"
$PN"201"48;
"DQS9_B_C||TDQS9_B_C \B"
$PN"94"38;
"DQS9_B_T||TDQS9_B_T||DBI4_B_N"
$PN"93"58;
%"Q_RES"
"1","(-2975,1325)","0","pure_quanta","I180";
;
PART_NUMBER"CS04992FB07"
MATERIAL"CHIP"
VALUE"49.9"
$LOCATION"R3881"
CDS_LIB"pure_quanta"
PACK_TYPE"0402LF"
TOLERANCE"1%"
WATTAGE"1/16W"
CDS_LOCATION"R3881"
$SEC"1"
CDS_SEC"1";
"B"
$PN"2"20;
"A"
$PN"1"26;
%"Q_RES"
"2","(-1675,-100)","0","pure_quanta","I2";
;
PART_NUMBER"CS41272FB07"
WATTAGE"1/16W"
PACK_TYPE"0402LF"
MATERIAL"CHIP"
TOLERANCE"1%"
VALUE"127K"
$LOCATION"R32"
CDS_LIB"pure_quanta"
CDS_LOCATION"R32"
$SEC"1"
CDS_SEC"1";
"A"
$PN"1"178;
"B"
$PN"2"5;
%"TAP"
"1","(-1900,2000)","2","standard","I26";
;
CDS_LIB"standard"
BODY_TYPE"PLUMBING"
HDL_TAP"TRUE";
"B \NAC \NWC"12;
"S \NAC"
BN"3"151;
%"TAP"
"1","(-1900,1950)","2","standard","I27";
;
CDS_LIB"standard"
BODY_TYPE"PLUMBING"
HDL_TAP"TRUE";
"B \NAC \NWC"12;
"S \NAC"
BN"2"150;
%"TAP"
"1","(-1900,2050)","2","standard","I28";
;
CDS_LIB"standard"
BODY_TYPE"PLUMBING"
HDL_TAP"TRUE";
"B \NAC \NWC"12;
"S \NAC"
BN"4"152;
%"TAP"
"1","(-1900,2100)","2","standard","I29";
;
CDS_LIB"standard"
BODY_TYPE"PLUMBING"
HDL_TAP"TRUE";
"B \NAC \NWC"12;
"S \NAC"
BN"5"153;
%"TAP"
"1","(-1900,2150)","2","standard","I30";
;
CDS_LIB"standard"
BODY_TYPE"PLUMBING"
HDL_TAP"TRUE";
"B \NAC \NWC"12;
"S \NAC"
BN"6"154;
%"TAP"
"1","(-1900,2200)","2","standard","I31";
;
CDS_LIB"standard"
BODY_TYPE"PLUMBING"
HDL_TAP"TRUE";
"B \NAC \NWC"12;
"S \NAC"
BN"7"173;
%"TAP"
"1","(-1900,2300)","2","standard","I32";
;
CDS_LIB"standard"
BODY_TYPE"PLUMBING"
HDL_TAP"TRUE";
"B \NAC \NWC"11;
"S \NAC"
BN"0"155;
%"TAP"
"1","(-1900,2400)","2","standard","I33";
;
CDS_LIB"standard"
BODY_TYPE"PLUMBING"
HDL_TAP"TRUE";
"B \NAC \NWC"11;
"S \NAC"
BN"2"156;
%"TAP"
"1","(-1900,2350)","2","standard","I34";
;
CDS_LIB"standard"
BODY_TYPE"PLUMBING"
HDL_TAP"TRUE";
"B \NAC \NWC"11;
"S \NAC"
BN"1"174;
%"TAP"
"1","(-1900,2450)","2","standard","I35";
;
CDS_LIB"standard"
BODY_TYPE"PLUMBING"
HDL_TAP"TRUE";
"B \NAC \NWC"11;
"S \NAC"
BN"3"157;
%"TAP"
"1","(-1900,2550)","2","standard","I36";
;
CDS_LIB"standard"
BODY_TYPE"PLUMBING"
HDL_TAP"TRUE";
"B \NAC \NWC"11;
"S \NAC"
BN"5"158;
%"TAP"
"1","(-1900,2500)","2","standard","I37";
;
CDS_LIB"standard"
BODY_TYPE"PLUMBING"
HDL_TAP"TRUE";
"B \NAC \NWC"11;
"S \NAC"
BN"4"175;
%"TAP"
"1","(-1900,2600)","2","standard","I38";
;
CDS_LIB"standard"
BODY_TYPE"PLUMBING"
HDL_TAP"TRUE";
"B \NAC \NWC"11;
"S \NAC"
BN"6"159;
%"TAP"
"1","(-1900,2650)","2","standard","I39";
;
CDS_LIB"standard"
BODY_TYPE"PLUMBING"
HDL_TAP"TRUE";
"B \NAC \NWC"11;
"S \NAC"
BN"7"176;
%"TAP"
"1","(-1900,3350)","2","standard","I40";
;
CDS_LIB"standard"
BODY_TYPE"PLUMBING"
HDL_TAP"TRUE";
"B \NAC \NWC"13;
"S \NAC"
BN"0"172;
%"TAP"
"1","(-1900,3450)","2","standard","I41";
;
CDS_LIB"standard"
BODY_TYPE"PLUMBING"
HDL_TAP"TRUE";
"B \NAC \NWC"13;
"S \NAC"
BN"2"168;
%"TAP"
"1","(-1900,3400)","2","standard","I42";
;
CDS_LIB"standard"
BODY_TYPE"PLUMBING"
HDL_TAP"TRUE";
"B \NAC \NWC"13;
"S \NAC"
BN"1"170;
%"TAP"
"1","(-1900,3500)","2","standard","I43";
;
CDS_LIB"standard"
BODY_TYPE"PLUMBING"
HDL_TAP"TRUE";
"B \NAC \NWC"13;
"S \NAC"
BN"3"166;
%"TAP"
"1","(-1900,3550)","2","standard","I44";
;
CDS_LIB"standard"
BODY_TYPE"PLUMBING"
HDL_TAP"TRUE";
"B \NAC \NWC"13;
"S \NAC"
BN"4"164;
%"TAP"
"1","(-1900,3600)","2","standard","I45";
;
CDS_LIB"standard"
BODY_TYPE"PLUMBING"
HDL_TAP"TRUE";
"B \NAC \NWC"13;
"S \NAC"
BN"5"162;
%"TAP"
"1","(-1900,3650)","2","standard","I46";
;
CDS_LIB"standard"
BODY_TYPE"PLUMBING"
HDL_TAP"TRUE";
"B \NAC \NWC"13;
"S \NAC"
BN"6"160;
%"TAP"
"1","(-1900,3800)","2","standard","I47";
;
CDS_LIB"standard"
BODY_TYPE"PLUMBING"
HDL_TAP"TRUE";
"B \NAC \NWC"14;
"S \NAC"
BN"1"171;
%"TAP"
"1","(-1900,3750)","2","standard","I48";
;
CDS_LIB"standard"
BODY_TYPE"PLUMBING"
HDL_TAP"TRUE";
"B \NAC \NWC"14;
"S \NAC"
BN"0"72;
%"TAP"
"1","(-1900,3850)","2","standard","I49";
;
CDS_LIB"standard"
BODY_TYPE"PLUMBING"
HDL_TAP"TRUE";
"B \NAC \NWC"14;
"S \NAC"
BN"2"169;
%"TAP"
"1","(-1900,3950)","2","standard","I50";
;
CDS_LIB"standard"
BODY_TYPE"PLUMBING"
HDL_TAP"TRUE";
"B \NAC \NWC"14;
"S \NAC"
BN"4"165;
%"TAP"
"1","(-1900,3900)","2","standard","I51";
;
CDS_LIB"standard"
BODY_TYPE"PLUMBING"
HDL_TAP"TRUE";
"B \NAC \NWC"14;
"S \NAC"
BN"3"167;
%"TAP"
"1","(-250,900)","0","standard","I52";
;
CDS_LIB"standard"
BODY_TYPE"PLUMBING"
HDL_TAP"TRUE";
"B \NAC \NWC"15;
"S \NAC"
BN"1"87;
%"TAP"
"1","(-250,850)","0","standard","I53";
;
CDS_LIB"standard"
BODY_TYPE"PLUMBING"
HDL_TAP"TRUE";
"B \NAC \NWC"15;
"S \NAC"
BN"0"86;
%"TAP"
"1","(-250,950)","0","standard","I54";
;
CDS_LIB"standard"
BODY_TYPE"PLUMBING"
HDL_TAP"TRUE";
"B \NAC \NWC"15;
"S \NAC"
BN"2"88;
%"TAP"
"1","(-250,1050)","0","standard","I55";
;
CDS_LIB"standard"
BODY_TYPE"PLUMBING"
HDL_TAP"TRUE";
"B \NAC \NWC"15;
"S \NAC"
BN"4"90;
%"TAP"
"1","(-250,1000)","0","standard","I56";
;
CDS_LIB"standard"
BODY_TYPE"PLUMBING"
HDL_TAP"TRUE";
"B \NAC \NWC"15;
"S \NAC"
BN"3"89;
%"TAP"
"1","(-250,1100)","0","standard","I57";
;
CDS_LIB"standard"
BODY_TYPE"PLUMBING"
HDL_TAP"TRUE";
"B \NAC \NWC"15;
"S \NAC"
BN"5"91;
%"TAP"
"1","(-250,1150)","0","standard","I58";
;
CDS_LIB"standard"
BODY_TYPE"PLUMBING"
HDL_TAP"TRUE";
"B \NAC \NWC"15;
"S \NAC"
BN"6"92;
%"TAP"
"1","(-250,1200)","0","standard","I59";
;
CDS_LIB"standard"
BODY_TYPE"PLUMBING"
HDL_TAP"TRUE";
"B \NAC \NWC"15;
"S \NAC"
BN"7"93;
%"TAP"
"1","(-250,1250)","0","standard","I60";
;
CDS_LIB"standard"
BODY_TYPE"PLUMBING"
HDL_TAP"TRUE";
"B \NAC \NWC"15;
"S \NAC"
BN"8"94;
%"TAP"
"1","(-250,1300)","0","standard","I61";
;
CDS_LIB"standard"
BODY_TYPE"PLUMBING"
HDL_TAP"TRUE";
"B \NAC \NWC"15;
"S \NAC"
BN"9"95;
%"TAP"
"1","(-250,1400)","0","standard","I62";
;
CDS_LIB"standard"
BODY_TYPE"PLUMBING"
HDL_TAP"TRUE";
"B \NAC \NWC"15;
"S \NAC"
BN"11"97;
%"TAP"
"1","(-250,1350)","0","standard","I63";
;
CDS_LIB"standard"
BODY_TYPE"PLUMBING"
HDL_TAP"TRUE";
"B \NAC \NWC"15;
"S \NAC"
BN"10"96;
%"TAP"
"1","(-250,1450)","0","standard","I64";
;
CDS_LIB"standard"
BODY_TYPE"PLUMBING"
HDL_TAP"TRUE";
"B \NAC \NWC"15;
"S \NAC"
BN"12"98;
%"TAP"
"1","(-250,1500)","0","standard","I65";
;
CDS_LIB"standard"
BODY_TYPE"PLUMBING"
HDL_TAP"TRUE";
"B \NAC \NWC"15;
"S \NAC"
BN"13"99;
%"TAP"
"1","(-250,1550)","0","standard","I66";
;
CDS_LIB"standard"
BODY_TYPE"PLUMBING"
HDL_TAP"TRUE";
"B \NAC \NWC"15;
"S \NAC"
BN"14"100;
%"TAP"
"1","(-250,1600)","0","standard","I67";
;
CDS_LIB"standard"
BODY_TYPE"PLUMBING"
HDL_TAP"TRUE";
"B \NAC \NWC"15;
"S \NAC"
BN"15"101;
%"TAP"
"1","(-250,1650)","0","standard","I68";
;
CDS_LIB"standard"
BODY_TYPE"PLUMBING"
HDL_TAP"TRUE";
"B \NAC \NWC"15;
"S \NAC"
BN"16"102;
%"TAP"
"1","(-250,1700)","0","standard","I69";
;
CDS_LIB"standard"
BODY_TYPE"PLUMBING"
HDL_TAP"TRUE";
"B \NAC \NWC"15;
"S \NAC"
BN"17"76;
%"TAP"
"1","(-250,1750)","0","standard","I70";
;
CDS_LIB"standard"
BODY_TYPE"PLUMBING"
HDL_TAP"TRUE";
"B \NAC \NWC"15;
"S \NAC"
BN"18"103;
%"TAP"
"1","(-250,1800)","0","standard","I71";
;
CDS_LIB"standard"
BODY_TYPE"PLUMBING"
HDL_TAP"TRUE";
"B \NAC \NWC"15;
"S \NAC"
BN"19"104;
%"TAP"
"1","(-250,1900)","0","standard","I72";
;
CDS_LIB"standard"
BODY_TYPE"PLUMBING"
HDL_TAP"TRUE";
"B \NAC \NWC"15;
"S \NAC"
BN"21"106;
%"TAP"
"1","(-250,1850)","0","standard","I73";
;
CDS_LIB"standard"
BODY_TYPE"PLUMBING"
HDL_TAP"TRUE";
"B \NAC \NWC"15;
"S \NAC"
BN"20"105;
%"TAP"
"1","(-250,1950)","0","standard","I74";
;
CDS_LIB"standard"
BODY_TYPE"PLUMBING"
HDL_TAP"TRUE";
"B \NAC \NWC"15;
"S \NAC"
BN"22"107;
%"TAP"
"1","(-250,2000)","0","standard","I75";
;
CDS_LIB"standard"
BODY_TYPE"PLUMBING"
HDL_TAP"TRUE";
"B \NAC \NWC"15;
"S \NAC"
BN"23"108;
%"TAP"
"1","(-250,2050)","0","standard","I76";
;
CDS_LIB"standard"
BODY_TYPE"PLUMBING"
HDL_TAP"TRUE";
"B \NAC \NWC"15;
"S \NAC"
BN"24"109;
%"TAP"
"1","(-250,2100)","0","standard","I77";
;
CDS_LIB"standard"
BODY_TYPE"PLUMBING"
HDL_TAP"TRUE";
"B \NAC \NWC"15;
"S \NAC"
BN"25"110;
%"TAP"
"1","(-250,2200)","0","standard","I78";
;
CDS_LIB"standard"
BODY_TYPE"PLUMBING"
HDL_TAP"TRUE";
"B \NAC \NWC"15;
"S \NAC"
BN"27"112;
%"TAP"
"1","(-250,2150)","0","standard","I79";
;
CDS_LIB"standard"
BODY_TYPE"PLUMBING"
HDL_TAP"TRUE";
"B \NAC \NWC"15;
"S \NAC"
BN"26"111;
%"TAP"
"1","(-250,2250)","0","standard","I80";
;
CDS_LIB"standard"
BODY_TYPE"PLUMBING"
HDL_TAP"TRUE";
"B \NAC \NWC"15;
"S \NAC"
BN"28"113;
%"TAP"
"1","(-250,2300)","0","standard","I81";
;
CDS_LIB"standard"
BODY_TYPE"PLUMBING"
HDL_TAP"TRUE";
"B \NAC \NWC"15;
"S \NAC"
BN"29"114;
%"TAP"
"1","(-250,2400)","0","standard","I82";
;
CDS_LIB"standard"
BODY_TYPE"PLUMBING"
HDL_TAP"TRUE";
"B \NAC \NWC"15;
"S \NAC"
BN"31"116;
%"TAP"
"1","(-250,2350)","0","standard","I83";
;
CDS_LIB"standard"
BODY_TYPE"PLUMBING"
HDL_TAP"TRUE";
"B \NAC \NWC"15;
"S \NAC"
BN"30"115;
%"TAP"
"1","(-250,2500)","0","standard","I84";
;
CDS_LIB"standard"
BODY_TYPE"PLUMBING"
HDL_TAP"TRUE";
"B \NAC \NWC"10;
"S \NAC"
BN"0"117;
%"TAP"
"1","(-250,2550)","0","standard","I85";
;
CDS_LIB"standard"
BODY_TYPE"PLUMBING"
HDL_TAP"TRUE";
"B \NAC \NWC"10;
"S \NAC"
BN"1"118;
%"TAP"
"1","(-250,2600)","0","standard","I86";
;
CDS_LIB"standard"
BODY_TYPE"PLUMBING"
HDL_TAP"TRUE";
"B \NAC \NWC"10;
"S \NAC"
BN"2"119;
%"TAP"
"1","(-250,2650)","0","standard","I87";
;
CDS_LIB"standard"
BODY_TYPE"PLUMBING"
HDL_TAP"TRUE";
"B \NAC \NWC"10;
"S \NAC"
BN"3"120;
%"TAP"
"1","(-250,2700)","0","standard","I88";
;
CDS_LIB"standard"
BODY_TYPE"PLUMBING"
HDL_TAP"TRUE";
"B \NAC \NWC"10;
"S \NAC"
BN"4"121;
%"TAP"
"1","(-250,2750)","0","standard","I89";
;
CDS_LIB"standard"
BODY_TYPE"PLUMBING"
HDL_TAP"TRUE";
"B \NAC \NWC"10;
"S \NAC"
BN"5"122;
%"TAP"
"1","(-250,2800)","0","standard","I90";
;
CDS_LIB"standard"
BODY_TYPE"PLUMBING"
HDL_TAP"TRUE";
"B \NAC \NWC"10;
"S \NAC"
BN"6"123;
%"TAP"
"1","(-250,2850)","0","standard","I91";
;
CDS_LIB"standard"
BODY_TYPE"PLUMBING"
HDL_TAP"TRUE";
"B \NAC \NWC"10;
"S \NAC"
BN"7"124;
%"TAP"
"1","(-250,2900)","0","standard","I92";
;
CDS_LIB"standard"
BODY_TYPE"PLUMBING"
HDL_TAP"TRUE";
"B \NAC \NWC"10;
"S \NAC"
BN"8"125;
%"TAP"
"1","(-250,2950)","0","standard","I93";
;
CDS_LIB"standard"
BODY_TYPE"PLUMBING"
HDL_TAP"TRUE";
"B \NAC \NWC"10;
"S \NAC"
BN"9"126;
%"TAP"
"1","(-250,3000)","0","standard","I94";
;
CDS_LIB"standard"
BODY_TYPE"PLUMBING"
HDL_TAP"TRUE";
"B \NAC \NWC"10;
"S \NAC"
BN"10"127;
%"TAP"
"1","(-250,3050)","0","standard","I95";
;
CDS_LIB"standard"
BODY_TYPE"PLUMBING"
HDL_TAP"TRUE";
"B \NAC \NWC"10;
"S \NAC"
BN"11"128;
%"TAP"
"1","(-250,3100)","0","standard","I96";
;
CDS_LIB"standard"
BODY_TYPE"PLUMBING"
HDL_TAP"TRUE";
"B \NAC \NWC"10;
"S \NAC"
BN"12"129;
%"TAP"
"1","(-250,3200)","0","standard","I97";
;
CDS_LIB"standard"
BODY_TYPE"PLUMBING"
HDL_TAP"TRUE";
"B \NAC \NWC"10;
"S \NAC"
BN"14"131;
%"TAP"
"1","(-250,3150)","0","standard","I98";
;
CDS_LIB"standard"
BODY_TYPE"PLUMBING"
HDL_TAP"TRUE";
"B \NAC \NWC"10;
"S \NAC"
BN"13"130;
%"TAP"
"1","(-250,3250)","0","standard","I99";
;
CDS_LIB"standard"
BODY_TYPE"PLUMBING"
HDL_TAP"TRUE";
"B \NAC \NWC"10;
"S \NAC"
BN"15"132;
END.
